(kicad_pcb
	(version 20260206)
	(generator "pcbnew")
	(generator_version "10.0")
	(general
		(thickness 1.6)
		(legacy_teardrops no)
	)
	(paper "A4")
	(title_block
		(title "9054_F0T_PDB_BD_GPU_F_V04_1213_1550_OCP.brd")
		(comment 1 "Grand Teton / footprints 344-346 of 608")
	)
	(layers
		(0 "F.Cu" signal "TOP")
		(4 "In1.Cu" signal "GND")
		(6 "In2.Cu" signal "IN1")
		(8 "In3.Cu" signal "GND1")
		(10 "In4.Cu" signal "VCC")
		(12 "In5.Cu" signal "VCC1")
		(14 "In6.Cu" signal "GND2")
		(16 "In7.Cu" signal "IN2")
		(18 "In8.Cu" signal "GND3")
		(2 "B.Cu" signal "BOTTOM")
		(9 "F.Adhes" user "F.Adhesive")
		(11 "B.Adhes" user "B.Adhesive")
		(13 "F.Paste" user "Package Geometry/Pastemask Top")
		(15 "B.Paste" user "Package Geometry/Pastemask Bottom")
		(5 "F.SilkS" user "Ref Des/Silkscreen Top")
		(7 "B.SilkS" user "Ref Des/Silkscreen Bottom")
		(1 "F.Mask" user "Board Geometry/Soldermask Top")
		(3 "B.Mask" user "Board Geometry/Soldermask Bottom")
		(17 "Dwgs.User" user "User.Drawings")
		(19 "Cmts.User" user "User.Comments")
		(21 "Eco1.User" user "User.Eco1")
		(23 "Eco2.User" user "User.Eco2")
		(25 "Edge.Cuts" user "Board Geometry/Outline")
		(27 "Margin" user)
		(31 "F.CrtYd" user "Package Geometry/Place Bound Top")
		(29 "B.CrtYd" user "Package Geometry/Place Bound Bottom")
		(35 "F.Fab" user "Ref Des/Assembly Top")
		(33 "B.Fab" user "Ref Des/Assembly Bottom")
	)
	(footprint ""
		(layer "F.Cu")
		(at 58.8264 -20.574)
		(property "Reference" "H25"
			(at -1.1684 -3.40233 0)
			(unlocked yes)
			(layer "F.SilkS")
			(effects
				(font
					(size 0.7874 0.5842)
					(thickness 0.1524)
				)
				(justify left)
			)
		)
		(property "Value" ""
			(at 0 0 0)
			(layer "F.Fab")
			(effects
				(font
					(size 1.27 1.27)
				)
			)
		)
		(duplicate_pad_numbers_are_jumpers no)
		(fp_circle
			(center 0 0)
			(end 2.4003 0)
			(stroke
				(width 0.1524)
				(type default)
			)
			(fill no)
			(layer "F.SilkS")
		)
		(fp_circle
			(center 0 0)
			(end 6.5913 0)
			(stroke
				(width 0.1524)
				(type default)
			)
			(fill no)
			(layer "B.SilkS")
		)
		(fp_circle
			(center 0 0)
			(end 6.5913 0)
			(stroke
				(width 0.1)
				(type default)
			)
			(fill no)
			(layer "B.Fab")
		)
		(fp_circle
			(center 0 0)
			(end 2.4003 0)
			(stroke
				(width 0.1)
				(type default)
			)
			(fill no)
			(layer "F.Fab")
		)
		(pad "" np_thru_hole circle
			(at 0 0)
			(size 3.175 3.175)
			(drill 3.175)
			(layers "*.Cu" "*.Mask")
			(clearance 0.381)
			(thermal_gap 0.381)
		)
		(zone
			(layers "F.Cu" "B.Cu" "In1.Cu" "In2.Cu" "In3.Cu" "In4.Cu" "In5.Cu" "In6.Cu"
				"In7.Cu" "In8.Cu"
			)
			(hatch none 0.5)
			(connect_pads
				(clearance 0)
			)
			(min_thickness 0.25)
			(keepout
				(tracks not_allowed)
				(vias allowed)
				(pads allowed)
				(copperpour not_allowed)
				(footprints allowed)
			)
			(placement
				(enabled no)
				(sheetname "")
			)
			(fill
				(thermal_gap 0.5)
				(thermal_bridge_width 0.5)
				(island_removal_mode 0)
			)
			(polygon
				(pts
					(arc
						(start 60.9219 -20.574)
						(mid 56.7309 -20.574)
						(end 60.9219 -20.574)
					)
				)
			)
		)
	)
	(footprint ""
		(layer "F.Cu")
		(at 34.874962 -168.82999)
		(property "Reference" "JP2"
			(at 3.606038 21.91766 0)
			(unlocked yes)
			(layer "F.SilkS")
			(effects
				(font
					(size 0.7874 0.5842)
					(thickness 0.1524)
				)
			)
		)
		(property "Value" ""
			(at 0 0 0)
			(layer "F.Fab")
			(effects
				(font
					(size 1.27 1.27)
				)
			)
		)
		(duplicate_pad_numbers_are_jumpers no)
		(fp_line
			(start -6.374892 -18.699988)
			(end 13.124942 -18.699988)
			(stroke
				(width 0.1524)
				(type default)
			)
			(layer "F.SilkS")
		)
		(fp_line
			(start -6.374892 20.999958)
			(end -6.374892 -18.699988)
			(stroke
				(width 0.1524)
				(type default)
			)
			(layer "F.SilkS")
		)
		(fp_line
			(start -3.374898 -15.699994)
			(end 10.124948 -15.699994)
			(stroke
				(width 0.1524)
				(type default)
			)
			(layer "F.SilkS")
		)
		(fp_line
			(start -3.374898 -6.500114)
			(end 10.124948 -6.500114)
			(stroke
				(width 0.1524)
				(type default)
			)
			(layer "F.SilkS")
		)
		(fp_line
			(start -3.374898 17.999964)
			(end -3.374898 -15.699994)
			(stroke
				(width 0.1524)
				(type default)
			)
			(layer "F.SilkS")
		)
		(fp_line
			(start 10.124948 -15.699994)
			(end 10.124948 17.999964)
			(stroke
				(width 0.1524)
				(type default)
			)
			(layer "F.SilkS")
		)
		(fp_line
			(start 10.124948 17.999964)
			(end -3.374898 17.999964)
			(stroke
				(width 0.1524)
				(type default)
			)
			(layer "F.SilkS")
		)
		(fp_line
			(start 13.124942 -18.699988)
			(end 13.124942 20.999958)
			(stroke
				(width 0.1524)
				(type default)
			)
			(layer "F.SilkS")
		)
		(fp_line
			(start 13.124942 20.999958)
			(end -6.374892 20.999958)
			(stroke
				(width 0.1524)
				(type default)
			)
			(layer "F.SilkS")
		)
		(fp_poly
			(pts
				(xy -2.048256 -0.381) (xy -2.048256 0.635) (xy -1.032256 0.127)
			)
			(stroke
				(width 0)
				(type default)
			)
			(fill yes)
			(layer "F.SilkS")
		)
		(fp_line
			(start -6.374892 -18.699988)
			(end 13.124942 -18.699988)
			(stroke
				(width 0.1524)
				(type default)
			)
			(layer "B.SilkS")
		)
		(fp_line
			(start -6.374892 20.999958)
			(end -6.374892 -18.699988)
			(stroke
				(width 0.1524)
				(type default)
			)
			(layer "B.SilkS")
		)
		(fp_line
			(start 13.124942 -18.699988)
			(end 13.124942 20.999958)
			(stroke
				(width 0.1524)
				(type default)
			)
			(layer "B.SilkS")
		)
		(fp_line
			(start 13.124942 20.999958)
			(end -6.374892 20.999958)
			(stroke
				(width 0.1524)
				(type default)
			)
			(layer "B.SilkS")
		)
		(fp_line
			(start -6.374892 -18.699988)
			(end 13.124942 -18.699988)
			(stroke
				(width 0.1)
				(type default)
			)
			(layer "B.Fab")
		)
		(fp_line
			(start -6.374892 20.999958)
			(end -6.374892 -18.699988)
			(stroke
				(width 0.1)
				(type default)
			)
			(layer "B.Fab")
		)
		(fp_line
			(start 13.124942 -18.699988)
			(end 13.124942 20.999958)
			(stroke
				(width 0.1)
				(type default)
			)
			(layer "B.Fab")
		)
		(fp_line
			(start 13.124942 20.999958)
			(end -6.374892 20.999958)
			(stroke
				(width 0.1)
				(type default)
			)
			(layer "B.Fab")
		)
		(fp_line
			(start -3.374898 -15.699994)
			(end 10.124948 -15.699994)
			(stroke
				(width 0.1)
				(type default)
			)
			(layer "F.Fab")
		)
		(fp_line
			(start -3.374898 17.999964)
			(end -3.374898 -15.699994)
			(stroke
				(width 0.1)
				(type default)
			)
			(layer "F.Fab")
		)
		(fp_line
			(start 10.124948 -15.699994)
			(end 10.124948 17.999964)
			(stroke
				(width 0.1)
				(type default)
			)
			(layer "F.Fab")
		)
		(fp_line
			(start 10.124948 17.999964)
			(end -3.374898 17.999964)
			(stroke
				(width 0.1)
				(type default)
			)
			(layer "F.Fab")
		)
		(fp_poly
			(pts
				(xy -4.842256 -0.508) (xy -4.842256 0.508) (xy -3.826256 0)
			)
			(stroke
				(width 0)
				(type default)
			)
			(fill yes)
			(layer "F.Fab")
		)
		(fp_text user "PRESS-FIT"
			(at -4.8768 19.94535 0)
			(unlocked yes)
			(layer "F.SilkS")
			(effects
				(font
					(size 1.905 1.4224)
					(thickness 0.1524)
				)
				(justify left)
			)
		)
		(fp_text user "PRESS-FIT"
			(at -2.369312 16.42999 270)
			(unlocked yes)
			(layer "B.SilkS")
			(effects
				(font
					(size 1.905 1.4224)
					(thickness 0.1524)
				)
				(justify left mirror)
			)
		)
		(fp_text user "PRESS-FIT"
			(at 11.811 19.94535 0)
			(unlocked yes)
			(layer "B.Fab")
			(effects
				(font
					(size 1.905 1.4224)
					(thickness 0.1524)
				)
				(justify left mirror)
			)
		)
		(fp_text user "PRESS-FIT"
			(at -4.8768 19.94535 0)
			(unlocked yes)
			(layer "F.Fab")
			(effects
				(font
					(size 1.905 1.4224)
					(thickness 0.1524)
				)
				(justify left)
			)
		)
		(pad "P1_1" thru_hole rect
			(at 0 0)
			(size 1.156208 1.156208)
			(drill 0.749808)
			(layers "*.Cu" "*.Mask")
			(remove_unused_layers no)
			(net "P52V_HS2")
			(clearance 0.0508)
			(thermal_gap 0.0508)
			(padstack
				(mode front_inner_back)
				(layer "Inner"
					(shape circle)
					(size 1.156208 1.156208)
					(clearance 0.0508)
				)
				(layer "B.Cu"
					(shape rect)
					(size 1.156208 1.156208)
					(clearance 0.0508)
				)
			)
		)
		(pad "P1_2" thru_hole circle
			(at 0 1.999996)
			(size 1.156208 1.156208)
			(drill 0.749808)
			(layers "*.Cu" "*.Mask")
			(remove_unused_layers no)
			(net "P52V_HS2")
			(clearance 0.0508)
			(thermal_gap 0.0508)
		)
		(pad "P1_3" thru_hole circle
			(at 0 3.999992)
			(size 1.156208 1.156208)
			(drill 0.749808)
			(layers "*.Cu" "*.Mask")
			(remove_unused_layers no)
			(net "P52V_HS2")
			(clearance 0.0508)
			(thermal_gap 0.0508)
		)
		(pad "P1_4" thru_hole circle
			(at 0 5.999988)
			(size 1.156208 1.156208)
			(drill 0.749808)
			(layers "*.Cu" "*.Mask")
			(remove_unused_layers no)
			(net "P52V_HS2")
			(clearance 0.0508)
			(thermal_gap 0.0508)
		)
		(pad "P1_5" thru_hole circle
			(at 0 7.999984)
			(size 1.156208 1.156208)
			(drill 0.749808)
			(layers "*.Cu" "*.Mask")
			(remove_unused_layers no)
			(net "P52V_HS2")
			(clearance 0.0508)
			(thermal_gap 0.0508)
		)
		(pad "P1_6" thru_hole circle
			(at 0 9.99998)
			(size 1.156208 1.156208)
			(drill 0.749808)
			(layers "*.Cu" "*.Mask")
			(remove_unused_layers no)
			(net "P52V_HS2")
			(clearance 0.0508)
			(thermal_gap 0.0508)
		)
		(pad "P1_7" thru_hole circle
			(at 0 11.999976)
			(size 1.156208 1.156208)
			(drill 0.749808)
			(layers "*.Cu" "*.Mask")
			(remove_unused_layers no)
			(net "P52V_HS2")
			(clearance 0.0508)
			(thermal_gap 0.0508)
		)
		(pad "P1_8" thru_hole circle
			(at 0 13.999972)
			(size 1.156208 1.156208)
			(drill 0.749808)
			(layers "*.Cu" "*.Mask")
			(remove_unused_layers no)
			(net "P52V_HS2")
			(clearance 0.0508)
			(thermal_gap 0.0508)
		)
		(pad "P1_9" thru_hole circle
			(at 0 15.999968)
			(size 1.156208 1.156208)
			(drill 0.749808)
			(layers "*.Cu" "*.Mask")
			(remove_unused_layers no)
			(net "P52V_HS2")
			(clearance 0.0508)
			(thermal_gap 0.0508)
		)
		(pad "P1_10" thru_hole circle
			(at 1.999996 0)
			(size 1.156208 1.156208)
			(drill 0.749808)
			(layers "*.Cu" "*.Mask")
			(remove_unused_layers no)
			(net "P52V_HS2")
			(clearance 0.0508)
			(thermal_gap 0.0508)
		)
		(pad "P1_11" thru_hole circle
			(at 1.999996 1.999996)
			(size 1.156208 1.156208)
			(drill 0.749808)
			(layers "*.Cu" "*.Mask")
			(remove_unused_layers no)
			(net "P52V_HS2")
			(clearance 0.0508)
			(thermal_gap 0.0508)
		)
		(pad "P1_12" thru_hole circle
			(at 1.999996 3.999992)
			(size 1.156208 1.156208)
			(drill 0.749808)
			(layers "*.Cu" "*.Mask")
			(remove_unused_layers no)
			(net "P52V_HS2")
			(clearance 0.0508)
			(thermal_gap 0.0508)
		)
		(pad "P1_13" thru_hole circle
			(at 1.999996 5.999988)
			(size 1.156208 1.156208)
			(drill 0.749808)
			(layers "*.Cu" "*.Mask")
			(remove_unused_layers no)
			(net "P52V_HS2")
			(clearance 0.0508)
			(thermal_gap 0.0508)
		)
		(pad "P1_14" thru_hole circle
			(at 1.999996 7.999984)
			(size 1.156208 1.156208)
			(drill 0.749808)
			(layers "*.Cu" "*.Mask")
			(remove_unused_layers no)
			(net "P52V_HS2")
			(clearance 0.0508)
			(thermal_gap 0.0508)
		)
		(pad "P1_15" thru_hole circle
			(at 1.999996 9.99998)
			(size 1.156208 1.156208)
			(drill 0.749808)
			(layers "*.Cu" "*.Mask")
			(remove_unused_layers no)
			(net "P52V_HS2")
			(clearance 0.0508)
			(thermal_gap 0.0508)
		)
		(pad "P1_16" thru_hole circle
			(at 1.999996 11.999976)
			(size 1.156208 1.156208)
			(drill 0.749808)
			(layers "*.Cu" "*.Mask")
			(remove_unused_layers no)
			(net "P52V_HS2")
			(clearance 0.0508)
			(thermal_gap 0.0508)
		)
		(pad "P1_17" thru_hole circle
			(at 1.999996 13.999972)
			(size 1.156208 1.156208)
			(drill 0.749808)
			(layers "*.Cu" "*.Mask")
			(remove_unused_layers no)
			(net "P52V_HS2")
			(clearance 0.0508)
			(thermal_gap 0.0508)
		)
		(pad "P1_18" thru_hole circle
			(at 1.999996 15.999968)
			(size 1.156208 1.156208)
			(drill 0.749808)
			(layers "*.Cu" "*.Mask")
			(remove_unused_layers no)
			(net "P52V_HS2")
			(clearance 0.0508)
			(thermal_gap 0.0508)
		)
		(pad "P2_1" thru_hole circle
			(at 4.750054 0)
			(size 1.156208 1.156208)
			(drill 0.749808)
			(layers "*.Cu" "*.Mask")
			(remove_unused_layers no)
			(net "GND")
			(clearance 0.0508)
			(thermal_gap 0.0508)
		)
		(pad "P2_2" thru_hole circle
			(at 4.750054 1.999996)
			(size 1.156208 1.156208)
			(drill 0.749808)
			(layers "*.Cu" "*.Mask")
			(remove_unused_layers no)
			(net "GND")
			(clearance 0.0508)
			(thermal_gap 0.0508)
		)
		(pad "P2_3" thru_hole circle
			(at 4.750054 3.999992)
			(size 1.156208 1.156208)
			(drill 0.749808)
			(layers "*.Cu" "*.Mask")
			(remove_unused_layers no)
			(net "GND")
			(clearance 0.0508)
			(thermal_gap 0.0508)
		)
		(pad "P2_4" thru_hole circle
			(at 4.750054 5.999988)
			(size 1.156208 1.156208)
			(drill 0.749808)
			(layers "*.Cu" "*.Mask")
			(remove_unused_layers no)
			(net "GND")
			(clearance 0.0508)
			(thermal_gap 0.0508)
		)
		(pad "P2_5" thru_hole circle
			(at 4.750054 7.999984)
			(size 1.156208 1.156208)
			(drill 0.749808)
			(layers "*.Cu" "*.Mask")
			(remove_unused_layers no)
			(net "GND")
			(clearance 0.0508)
			(thermal_gap 0.0508)
		)
		(pad "P2_6" thru_hole circle
			(at 4.750054 9.99998)
			(size 1.156208 1.156208)
			(drill 0.749808)
			(layers "*.Cu" "*.Mask")
			(remove_unused_layers no)
			(net "GND")
			(clearance 0.0508)
			(thermal_gap 0.0508)
		)
		(pad "P2_7" thru_hole circle
			(at 4.750054 11.999976)
			(size 1.156208 1.156208)
			(drill 0.749808)
			(layers "*.Cu" "*.Mask")
			(remove_unused_layers no)
			(net "GND")
			(clearance 0.0508)
			(thermal_gap 0.0508)
		)
		(pad "P2_8" thru_hole circle
			(at 4.750054 13.999972)
			(size 1.156208 1.156208)
			(drill 0.749808)
			(layers "*.Cu" "*.Mask")
			(remove_unused_layers no)
			(net "GND")
			(clearance 0.0508)
			(thermal_gap 0.0508)
		)
		(pad "P2_9" thru_hole circle
			(at 4.750054 15.999968)
			(size 1.156208 1.156208)
			(drill 0.749808)
			(layers "*.Cu" "*.Mask")
			(remove_unused_layers no)
			(net "GND")
			(clearance 0.0508)
			(thermal_gap 0.0508)
		)
		(pad "P2_10" thru_hole circle
			(at 6.75005 0)
			(size 1.156208 1.156208)
			(drill 0.749808)
			(layers "*.Cu" "*.Mask")
			(remove_unused_layers no)
			(net "GND")
			(clearance 0.0508)
			(thermal_gap 0.0508)
		)
		(pad "P2_11" thru_hole circle
			(at 6.75005 1.999996)
			(size 1.156208 1.156208)
			(drill 0.749808)
			(layers "*.Cu" "*.Mask")
			(remove_unused_layers no)
			(net "GND")
			(clearance 0.0508)
			(thermal_gap 0.0508)
		)
		(pad "P2_12" thru_hole circle
			(at 6.75005 3.999992)
			(size 1.156208 1.156208)
			(drill 0.749808)
			(layers "*.Cu" "*.Mask")
			(remove_unused_layers no)
			(net "GND")
			(clearance 0.0508)
			(thermal_gap 0.0508)
		)
		(pad "P2_13" thru_hole circle
			(at 6.75005 5.999988)
			(size 1.156208 1.156208)
			(drill 0.749808)
			(layers "*.Cu" "*.Mask")
			(remove_unused_layers no)
			(net "GND")
			(clearance 0.0508)
			(thermal_gap 0.0508)
		)
		(pad "P2_14" thru_hole circle
			(at 6.75005 7.999984)
			(size 1.156208 1.156208)
			(drill 0.749808)
			(layers "*.Cu" "*.Mask")
			(remove_unused_layers no)
			(net "GND")
			(clearance 0.0508)
			(thermal_gap 0.0508)
		)
		(pad "P2_15" thru_hole circle
			(at 6.75005 9.99998)
			(size 1.156208 1.156208)
			(drill 0.749808)
			(layers "*.Cu" "*.Mask")
			(remove_unused_layers no)
			(net "GND")
			(clearance 0.0508)
			(thermal_gap 0.0508)
		)
		(pad "P2_16" thru_hole circle
			(at 6.75005 11.999976)
			(size 1.156208 1.156208)
			(drill 0.749808)
			(layers "*.Cu" "*.Mask")
			(remove_unused_layers no)
			(net "GND")
			(clearance 0.0508)
			(thermal_gap 0.0508)
		)
		(pad "P2_17" thru_hole circle
			(at 6.75005 13.999972)
			(size 1.156208 1.156208)
			(drill 0.749808)
			(layers "*.Cu" "*.Mask")
			(remove_unused_layers no)
			(net "GND")
			(clearance 0.0508)
			(thermal_gap 0.0508)
		)
		(pad "P2_18" thru_hole circle
			(at 6.75005 15.999968)
			(size 1.156208 1.156208)
			(drill 0.749808)
			(layers "*.Cu" "*.Mask")
			(remove_unused_layers no)
			(net "GND")
			(clearance 0.0508)
			(thermal_gap 0.0508)
		)
		(zone
			(layer "B.Cu")
			(hatch none 0.5)
			(connect_pads
				(clearance 0)
			)
			(min_thickness 0.25)
			(keepout
				(tracks allowed)
				(vias not_allowed)
				(pads allowed)
				(copperpour not_allowed)
				(footprints allowed)
			)
			(placement
				(enabled no)
				(sheetname "")
			)
			(fill
				(thermal_gap 0.5)
				(thermal_bridge_width 0.5)
				(island_removal_mode 0)
			)
			(polygon
				(pts
					(xy 34.233358 -169.471594) (xy 34.233358 -152.188418) (xy 42.266616 -152.188418) (xy 42.266616 -169.471594)
				)
			)
		)
	)
	(footprint ""
		(layer "F.Cu")
		(at 436.245 -27.813 180)
		(property "Reference" "R328"
			(at 0 0 180)
			(layer "F.SilkS")
			(hide yes)
			(effects
				(font
					(size 1.27 1.27)
				)
			)
		)
		(property "Value" ""
			(at 0 0 180)
			(layer "F.Fab")
			(effects
				(font
					(size 1.27 1.27)
				)
			)
		)
		(duplicate_pad_numbers_are_jumpers no)
		(fp_line
			(start 0.7874 0.4064)
			(end -0.7874 0.4064)
			(stroke
				(width 0.1524)
				(type default)
			)
			(layer "F.SilkS")
		)
		(fp_line
			(start 0.7874 -0.4064)
			(end 0.7874 0.4064)
			(stroke
				(width 0.1524)
				(type default)
			)
			(layer "F.SilkS")
		)
		(fp_line
			(start -0.7874 0.4064)
			(end -0.7874 -0.4064)
			(stroke
				(width 0.1524)
				(type default)
			)
			(layer "F.SilkS")
		)
		(fp_line
			(start -0.7874 -0.4064)
			(end 0.7874 -0.4064)
			(stroke
				(width 0.1524)
				(type default)
			)
			(layer "F.SilkS")
		)
		(fp_line
			(start 0.67945 0.3048)
			(end 0.120396 0.3048)
			(stroke
				(width 0.1)
				(type default)
			)
			(layer "F.Fab")
		)
		(fp_line
			(start 0.67945 -0.3048)
			(end 0.67945 0.3048)
			(stroke
				(width 0.1)
				(type default)
			)
			(layer "F.Fab")
		)
		(fp_line
			(start 0.12065 -0.2794)
			(end 0.12065 -0.3048)
			(stroke
				(width 0.1)
				(type default)
			)
			(layer "F.Fab")
		)
		(fp_line
			(start 0.12065 -0.3048)
			(end 0.67945 -0.3048)
			(stroke
				(width 0.1)
				(type default)
			)
			(layer "F.Fab")
		)
		(fp_line
			(start 0.120396 0.3048)
			(end 0.120396 0.2794)
			(stroke
				(width 0.1)
				(type default)
			)
			(layer "F.Fab")
		)
		(fp_line
			(start 0.120396 0.2794)
			(end -0.12065 0.2794)
			(stroke
				(width 0.1)
				(type default)
			)
			(layer "F.Fab")
		)
		(fp_line
			(start -0.12065 0.3048)
			(end -0.67945 0.3048)
			(stroke
				(width 0.1)
				(type default)
			)
			(layer "F.Fab")
		)
		(fp_line
			(start -0.12065 0.2794)
			(end -0.12065 0.3048)
			(stroke
				(width 0.1)
				(type default)
			)
			(layer "F.Fab")
		)
		(fp_line
			(start -0.12065 -0.2794)
			(end 0.12065 -0.2794)
			(stroke
				(width 0.1)
				(type default)
			)
			(layer "F.Fab")
		)
		(fp_line
			(start -0.12065 -0.305054)
			(end -0.12065 -0.2794)
			(stroke
				(width 0.1)
				(type default)
			)
			(layer "F.Fab")
		)
		(fp_line
			(start -0.67945 0.3048)
			(end -0.67945 -0.305054)
			(stroke
				(width 0.1)
				(type default)
			)
			(layer "F.Fab")
		)
		(fp_line
			(start -0.67945 -0.305054)
			(end -0.12065 -0.305054)
			(stroke
				(width 0.1)
				(type default)
			)
			(layer "F.Fab")
		)
		(pad "1" smd circle
			(at -0.40005 0 180)
			(size 0 0)
			(layers "F.Cu" "F.Mask" "F.Paste")
			(net "SMB_PDB_FAN_0_SCL")
		)
		(pad "2" smd circle
			(at 0.40005 0 180)
			(size 0 0)
			(layers "F.Cu" "F.Mask" "F.Paste")
			(net "P3V3_AUX")
		)
	)
)
